(kicad_pcb
	(version 20241229)
	(generator "pcbnew")
	(generator_version "9.0")
	(general
		(thickness 1.599998)
		(legacy_teardrops no)
	)
	(paper "A4")
	(title_block
		(date "2023-02-12")
		(rev "1.1.5")
		(comment 9 "footprints 69-75 of 473")
	)
	(layers
		(0 "F.Cu" signal)
		(4 "In1.Cu" power "In1.GND")
		(6 "In2.Cu" signal)
		(8 "In3.Cu" power "In3.GND")
		(10 "In4.Cu" power "In4.VCC")
		(12 "In5.Cu" signal)
		(14 "In6.Cu" power "In6.VCC")
		(2 "B.Cu" signal)
		(9 "F.Adhes" user "F.Adhesive")
		(11 "B.Adhes" user "B.Adhesive")
		(13 "F.Paste" user)
		(15 "B.Paste" user)
		(5 "F.SilkS" user "F.Silkscreen")
		(7 "B.SilkS" user "B.Silkscreen")
		(1 "F.Mask" user)
		(3 "B.Mask" user)
		(17 "Dwgs.User" user "User.Drawings")
		(19 "Cmts.User" user "User.Comments")
		(21 "Eco1.User" user "User.Eco1")
		(23 "Eco2.User" user "User.Eco2")
		(25 "Edge.Cuts" user)
		(27 "Margin" user)
		(31 "F.CrtYd" user "F.Courtyard")
		(29 "B.CrtYd" user "B.Courtyard")
		(35 "F.Fab" user)
		(33 "B.Fab" user)
	)
	(footprint "antmicro-footprints:R_0402_1005Metric"
		(layer "F.Cu")
		(at 180.1885 118.271)
		(descr "Resistor SMD 0402")
		(tags "resistor SMD 0402")
		(property "Reference" "R48"
			(at 0.8115 0.399 0)
			(layer "F.SilkS")
			(effects
				(font
					(size 0.7 0.7)
					(thickness 0.15)
				)
				(justify left bottom)
			)
		)
		(property "Value" "R_0R_0402"
			(at 0 1.4 0)
			(layer "F.Fab")
			(effects
				(font
					(size 0.7 0.7)
					(thickness 0.15)
				)
				(justify left bottom)
			)
		)
		(property "Description" "0R resistor in 0402 package with unspecified tolerance"
			(at 0 0 0)
			(layer "F.Fab")
			(hide yes)
			(effects
				(font
					(size 1.27 1.27)
					(thickness 0.15)
				)
			)
		)
		(property "Author" "Antmicro"
			(at 0 0 0)
			(layer "F.Fab")
			(hide yes)
			(effects
				(font
					(size 1 1)
					(thickness 0.15)
				)
			)
		)
		(property "Current" "1A"
			(at 0 0 0)
			(layer "F.Fab")
			(hide yes)
			(effects
				(font
					(size 1 1)
					(thickness 0.15)
				)
			)
		)
		(property "License" "Apache-2.0"
			(at 0 0 0)
			(layer "F.Fab")
			(hide yes)
			(effects
				(font
					(size 1 1)
					(thickness 0.15)
				)
			)
		)
		(property "MPN" "ERJ2GE0R00X"
			(at 0 0 0)
			(layer "F.Fab")
			(hide yes)
			(effects
				(font
					(size 1 1)
					(thickness 0.15)
				)
			)
		)
		(property "Manufacturer" "Panasonic"
			(at 0 0 0)
			(layer "F.Fab")
			(hide yes)
			(effects
				(font
					(size 1 1)
					(thickness 0.15)
				)
			)
		)
		(property "Tolerance" ""
			(at 0 0 0)
			(layer "F.Fab")
			(hide yes)
			(effects
				(font
					(size 1 1)
					(thickness 0.15)
				)
			)
		)
		(property "Val" "0R"
			(at 0 0 0)
			(layer "F.Fab")
			(hide yes)
			(effects
				(font
					(size 1 1)
					(thickness 0.15)
				)
			)
		)
		(sheetname "Config SPI flash")
		(sheetfile "config-spi.kicad_sch")
		(attr smd)
		(fp_rect
			(start -0.93 -0.47)
			(end 0.93 0.47)
			(stroke
				(width 0.05)
				(type solid)
			)
			(fill no)
			(layer "F.CrtYd")
		)
		(fp_rect
			(start -0.5 -0.25)
			(end 0.5 0.25)
			(stroke
				(width 0.15)
				(type solid)
			)
			(fill no)
			(layer "F.Fab")
		)
		(pad "1" smd roundrect
			(at -0.485 0)
			(size 0.59 0.64)
			(layers "F.Cu" "F.Mask" "F.Paste")
			(roundrect_rratio 0.25)
			(net 256 "Net-(U5-SCK)")
			(pintype "passive")
		)
		(pad "2" smd roundrect
			(at 0.485 0)
			(size 0.59 0.64)
			(layers "F.Cu" "F.Mask" "F.Paste")
			(roundrect_rratio 0.25)
			(net 213 "CCLK")
			(pintype "passive")
		)
	)
	(footprint "antmicro-footprints:R_0402_1005Metric"
		(layer "F.Cu")
		(at 202.386328 84.820008 180)
		(descr "Resistor SMD 0402")
		(tags "resistor SMD 0402")
		(property "Reference" "R57"
			(at 0.886328 0.520008 180)
			(layer "F.SilkS")
			(effects
				(font
					(size 0.7 0.7)
					(thickness 0.15)
				)
				(justify left bottom)
			)
		)
		(property "Value" "R_330R_0402"
			(at 0 1.4 180)
			(layer "F.Fab")
			(effects
				(font
					(size 0.7 0.7)
					(thickness 0.15)
				)
				(justify left bottom)
			)
		)
		(property "Description" "330R resistor in 0402 package with 1% tolerance"
			(at 0 0 180)
			(layer "F.Fab")
			(hide yes)
			(effects
				(font
					(size 1.27 1.27)
					(thickness 0.15)
				)
			)
		)
		(property "Author" "Antmicro"
			(at 404.772656 169.640016 0)
			(layer "F.Fab")
			(hide yes)
			(effects
				(font
					(size 1 1)
					(thickness 0.15)
				)
			)
		)
		(property "License" "Apache-2.0"
			(at 404.772656 169.640016 0)
			(layer "F.Fab")
			(hide yes)
			(effects
				(font
					(size 1 1)
					(thickness 0.15)
				)
			)
		)
		(property "MPN" "CR0402-FX-3300GLF"
			(at 404.772656 169.640016 0)
			(layer "F.Fab")
			(hide yes)
			(effects
				(font
					(size 1 1)
					(thickness 0.15)
				)
			)
		)
		(property "Manufacturer" "Bourns"
			(at 404.772656 169.640016 0)
			(layer "F.Fab")
			(hide yes)
			(effects
				(font
					(size 1 1)
					(thickness 0.15)
				)
			)
		)
		(property "Tolerance" "1%"
			(at 404.772656 169.640016 0)
			(layer "F.Fab")
			(hide yes)
			(effects
				(font
					(size 1 1)
					(thickness 0.15)
				)
			)
		)
		(property "Val" "330R"
			(at 404.772656 169.640016 0)
			(layer "F.Fab")
			(hide yes)
			(effects
				(font
					(size 1 1)
					(thickness 0.15)
				)
			)
		)
		(sheetname "Config SPI flash")
		(sheetfile "config-spi.kicad_sch")
		(attr smd)
		(fp_rect
			(start -0.93 -0.47)
			(end 0.93 0.47)
			(stroke
				(width 0.05)
				(type solid)
			)
			(fill no)
			(layer "F.CrtYd")
		)
		(fp_rect
			(start -0.5 -0.25)
			(end 0.5 0.25)
			(stroke
				(width 0.15)
				(type solid)
			)
			(fill no)
			(layer "F.Fab")
		)
		(pad "1" smd roundrect
			(at -0.485 0 180)
			(size 0.59 0.64)
			(layers "F.Cu" "F.Mask" "F.Paste")
			(roundrect_rratio 0.25)
			(net 54 "Net-(D8-Pad2)")
			(pintype "passive")
		)
		(pad "2" smd roundrect
			(at 0.485 0 180)
			(size 0.59 0.64)
			(layers "F.Cu" "F.Mask" "F.Paste")
			(roundrect_rratio 0.25)
			(net 232 "Net-(Q6-D)")
			(pintype "passive")
		)
	)
	(footprint "antmicro-footprints:C_0603_1608Metric"
		(layer "F.Cu")
		(at 139.5 98.249 180)
		(descr "Capacitor SMD 0603")
		(tags "capacitor 0603")
		(property "Reference" "C137"
			(at 1.6 -1.351 180)
			(layer "F.SilkS")
			(effects
				(font
					(size 0.7 0.7)
					(thickness 0.15)
				)
				(justify left bottom)
			)
		)
		(property "Value" "C_10n_0603"
			(at 0 1.6 180)
			(layer "F.Fab")
			(effects
				(font
					(size 0.7 0.7)
					(thickness 0.15)
				)
				(justify left bottom)
			)
		)
		(property "Description" " "
			(at 0 0 180)
			(layer "F.Fab")
			(hide yes)
			(effects
				(font
					(size 1.27 1.27)
					(thickness 0.15)
				)
			)
		)
		(property "Author" "Antmicro"
			(at 279 196.498 0)
			(layer "F.Fab")
			(hide yes)
			(effects
				(font
					(size 1 1)
					(thickness 0.15)
				)
			)
		)
		(property "Dielectric" ""
			(at 279 196.498 0)
			(layer "F.Fab")
			(hide yes)
			(effects
				(font
					(size 1 1)
					(thickness 0.15)
				)
			)
		)
		(property "License" "Apache-2.0"
			(at 279 196.498 0)
			(layer "F.Fab")
			(hide yes)
			(effects
				(font
					(size 1 1)
					(thickness 0.15)
				)
			)
		)
		(property "MPN" "06031C103JAT2A"
			(at 279 196.498 0)
			(layer "F.Fab")
			(hide yes)
			(effects
				(font
					(size 1 1)
					(thickness 0.15)
				)
			)
		)
		(property "Manufacturer" "AVX"
			(at 279 196.498 0)
			(layer "F.Fab")
			(hide yes)
			(effects
				(font
					(size 1 1)
					(thickness 0.15)
				)
			)
		)
		(property "Val" "10n"
			(at 279 196.498 0)
			(layer "F.Fab")
			(hide yes)
			(effects
				(font
					(size 1 1)
					(thickness 0.15)
				)
			)
		)
		(property "Voltage" ""
			(at 279 196.498 0)
			(layer "F.Fab")
			(hide yes)
			(effects
				(font
					(size 1 1)
					(thickness 0.15)
				)
			)
		)
		(sheetname "Supply")
		(sheetfile "supply.kicad_sch")
		(attr smd)
		(fp_line
			(start -0.3 0.3)
			(end 0.3 0.3)
			(stroke
				(width 0.15)
				(type solid)
			)
			(layer "F.SilkS")
		)
		(fp_line
			(start -0.3 -0.3)
			(end 0.3 -0.3)
			(stroke
				(width 0.15)
				(type solid)
			)
			(layer "F.SilkS")
		)
		(fp_rect
			(start -1.24 -0.7)
			(end 1.24 0.7)
			(stroke
				(width 0.05)
				(type solid)
			)
			(fill no)
			(layer "F.CrtYd")
		)
		(fp_rect
			(start -0.8 -0.4)
			(end 0.8 0.4)
			(stroke
				(width 0.15)
				(type solid)
			)
			(fill no)
			(layer "F.Fab")
		)
		(pad "1" smd roundrect
			(at -0.7 0 180)
			(size 0.6 0.8)
			(layers "F.Cu" "F.Mask" "F.Paste")
			(roundrect_rratio 0.2)
			(net 58 "Net-(U7-TADJ)")
			(pintype "passive")
		)
		(pad "2" smd roundrect
			(at 0.7 0 180)
			(size 0.6 0.8)
			(layers "F.Cu" "F.Mask" "F.Paste")
			(roundrect_rratio 0.2)
			(net 5 "GND")
			(pintype "passive")
		)
	)
	(footprint "antmicro-footprints:C_0402_1005Metric"
		(layer "F.Cu")
		(at 133.5 94.499 180)
		(descr "Capacitor SMD 0402")
		(tags "capacitor SMD 0402")
		(property "Reference" "C133"
			(at 1.8 -1.301 180)
			(layer "F.SilkS")
			(effects
				(font
					(size 0.7 0.7)
					(thickness 0.15)
				)
				(justify left bottom)
			)
		)
		(property "Value" "C_100n_6V3_0402"
			(at 0 1.4 180)
			(layer "F.Fab")
			(effects
				(font
					(size 0.7 0.7)
					(thickness 0.15)
				)
				(justify left bottom)
			)
		)
		(property "Description" " "
			(at 0 0 180)
			(layer "F.Fab")
			(hide yes)
			(effects
				(font
					(size 1.27 1.27)
					(thickness 0.15)
				)
			)
		)
		(property "Author" "Antmicro"
			(at 267 188.998 0)
			(layer "F.Fab")
			(hide yes)
			(effects
				(font
					(size 1 1)
					(thickness 0.15)
				)
			)
		)
		(property "Dielectric" ""
			(at 267 188.998 0)
			(layer "F.Fab")
			(hide yes)
			(effects
				(font
					(size 1 1)
					(thickness 0.15)
				)
			)
		)
		(property "License" "Apache-2.0"
			(at 267 188.998 0)
			(layer "F.Fab")
			(hide yes)
			(effects
				(font
					(size 1 1)
					(thickness 0.15)
				)
			)
		)
		(property "MPN" "0402X104K6R3CT"
			(at 267 188.998 0)
			(layer "F.Fab")
			(hide yes)
			(effects
				(font
					(size 1 1)
					(thickness 0.15)
				)
			)
		)
		(property "Manufacturer" "Walsin"
			(at 267 188.998 0)
			(layer "F.Fab")
			(hide yes)
			(effects
				(font
					(size 1 1)
					(thickness 0.15)
				)
			)
		)
		(property "Val" "100n"
			(at 267 188.998 0)
			(layer "F.Fab")
			(hide yes)
			(effects
				(font
					(size 1 1)
					(thickness 0.15)
				)
			)
		)
		(property "Voltage" ""
			(at 267 188.998 0)
			(layer "F.Fab")
			(hide yes)
			(effects
				(font
					(size 1 1)
					(thickness 0.15)
				)
			)
		)
		(sheetname "Supply")
		(sheetfile "supply.kicad_sch")
		(attr smd)
		(fp_rect
			(start -0.94 -0.47)
			(end 0.94 0.47)
			(stroke
				(width 0.05)
				(type solid)
			)
			(fill no)
			(layer "F.CrtYd")
		)
		(fp_rect
			(start -0.499 -0.249)
			(end 0.499 0.249)
			(stroke
				(width 0.15)
				(type solid)
			)
			(fill no)
			(layer "F.Fab")
		)
		(pad "1" smd roundrect
			(at -0.484 0 180)
			(size 0.59 0.64)
			(layers "F.Cu" "F.Mask" "F.Paste")
			(roundrect_rratio 0.25)
			(net 463 "VCC5V0_INT")
			(pintype "passive")
		)
		(pad "2" smd roundrect
			(at 0.484 0 180)
			(size 0.59 0.64)
			(layers "F.Cu" "F.Mask" "F.Paste")
			(roundrect_rratio 0.25)
			(net 5 "GND")
			(pintype "passive")
		)
	)
	(footprint "antmicro-footprints:R_0402_1005Metric"
		(layer "F.Cu")
		(at 136.5 98.249)
		(descr "Resistor SMD 0402")
		(tags "resistor SMD 0402")
		(property "Reference" "R106"
			(at -1.4 1.351 0)
			(layer "F.SilkS")
			(effects
				(font
					(size 0.7 0.7)
					(thickness 0.15)
				)
				(justify left bottom)
			)
		)
		(property "Value" "R_0R_0402"
			(at 0 1.4 0)
			(layer "F.Fab")
			(effects
				(font
					(size 0.7 0.7)
					(thickness 0.15)
				)
				(justify left bottom)
			)
		)
		(property "Description" "0R resistor in 0402 package with unspecified tolerance"
			(at 0 0 0)
			(layer "F.Fab")
			(hide yes)
			(effects
				(font
					(size 1.27 1.27)
					(thickness 0.15)
				)
			)
		)
		(property "Author" "Antmicro"
			(at 0 0 0)
			(layer "F.Fab")
			(hide yes)
			(effects
				(font
					(size 1 1)
					(thickness 0.15)
				)
			)
		)
		(property "Current" "1A"
			(at 0 0 0)
			(layer "F.Fab")
			(hide yes)
			(effects
				(font
					(size 1 1)
					(thickness 0.15)
				)
			)
		)
		(property "License" "Apache-2.0"
			(at 0 0 0)
			(layer "F.Fab")
			(hide yes)
			(effects
				(font
					(size 1 1)
					(thickness 0.15)
				)
			)
		)
		(property "MPN" "ERJ2GE0R00X"
			(at 0 0 0)
			(layer "F.Fab")
			(hide yes)
			(effects
				(font
					(size 1 1)
					(thickness 0.15)
				)
			)
		)
		(property "Manufacturer" "Panasonic"
			(at 0 0 0)
			(layer "F.Fab")
			(hide yes)
			(effects
				(font
					(size 1 1)
					(thickness 0.15)
				)
			)
		)
		(property "Tolerance" ""
			(at 0 0 0)
			(layer "F.Fab")
			(hide yes)
			(effects
				(font
					(size 1 1)
					(thickness 0.15)
				)
			)
		)
		(property "Val" "0R"
			(at 0 0 0)
			(layer "F.Fab")
			(hide yes)
			(effects
				(font
					(size 1 1)
					(thickness 0.15)
				)
			)
		)
		(sheetname "Supply")
		(sheetfile "supply.kicad_sch")
		(attr smd)
		(fp_rect
			(start -0.93 -0.47)
			(end 0.93 0.47)
			(stroke
				(width 0.05)
				(type solid)
			)
			(fill no)
			(layer "F.CrtYd")
		)
		(fp_rect
			(start -0.5 -0.25)
			(end 0.5 0.25)
			(stroke
				(width 0.15)
				(type solid)
			)
			(fill no)
			(layer "F.Fab")
		)
		(pad "1" smd roundrect
			(at -0.485 0)
			(size 0.59 0.64)
			(layers "F.Cu" "F.Mask" "F.Paste")
			(roundrect_rratio 0.25)
			(net 262 "Net-(U7-INV)")
			(pintype "passive")
		)
		(pad "2" smd roundrect
			(at 0.485 0)
			(size 0.59 0.64)
			(layers "F.Cu" "F.Mask" "F.Paste")
			(roundrect_rratio 0.25)
			(net 5 "GND")
			(pintype "passive")
		)
	)
	(footprint "antmicro-footprints:TP_SMD_1mm"
		(layer "F.Cu")
		(at 142.625 93.7998)
		(property "Reference" "TP10"
			(at 0.475 0.4002 0)
			(layer "F.SilkS")
			(effects
				(font
					(size 0.7 0.7)
					(thickness 0.15)
				)
				(justify left bottom)
			)
		)
		(property "Value" "TP_1mm_SMD"
			(at 0 1.4 0)
			(layer "F.Fab")
			(effects
				(font
					(size 0.7 0.7)
					(thickness 0.15)
				)
				(justify left bottom)
			)
		)
		(property "Description" "Test Point 1mm"
			(at 0 0 0)
			(layer "F.Fab")
			(hide yes)
			(effects
				(font
					(size 1.27 1.27)
					(thickness 0.15)
				)
			)
		)
		(property "Author" "Antmicro"
			(at 0 0 0)
			(layer "F.Fab")
			(hide yes)
			(effects
				(font
					(size 1 1)
					(thickness 0.15)
				)
			)
		)
		(property "License" "Apache-2.0"
			(at 0 0 0)
			(layer "F.Fab")
			(hide yes)
			(effects
				(font
					(size 1 1)
					(thickness 0.15)
				)
			)
		)
		(property "MPN" ""
			(at 0 0 0)
			(layer "F.Fab")
			(hide yes)
			(effects
				(font
					(size 1 1)
					(thickness 0.15)
				)
			)
		)
		(property "Manufacturer" ""
			(at 0 0 0)
			(layer "F.Fab")
			(hide yes)
			(effects
				(font
					(size 1 1)
					(thickness 0.15)
				)
			)
		)
		(sheetname "Supply")
		(sheetfile "supply.kicad_sch")
		(attr exclude_from_pos_files)
		(pad "1" smd circle
			(at 0 0)
			(size 1 1)
			(layers "F.Cu" "F.Mask")
			(net 468 "/Supply/VCC_INT_EN")
			(pinfunction "1")
			(pintype "passive")
		)
	)
	(footprint "antmicro-footprints:TP_SMD_1mm"
		(layer "F.Cu")
		(at 142.625 95.249)
		(property "Reference" "TP11"
			(at 0.375 0.351 0)
			(layer "F.SilkS")
			(effects
				(font
					(size 0.7 0.7)
					(thickness 0.15)
				)
				(justify left bottom)
			)
		)
		(property "Value" "TP_1mm_SMD"
			(at 0 1.4 0)
			(layer "F.Fab")
			(effects
				(font
					(size 0.7 0.7)
					(thickness 0.15)
				)
				(justify left bottom)
			)
		)
		(property "Description" "Test Point 1mm"
			(at 0 0 0)
			(layer "F.Fab")
			(hide yes)
			(effects
				(font
					(size 1.27 1.27)
					(thickness 0.15)
				)
			)
		)
		(property "Author" "Antmicro"
			(at 0 0 0)
			(layer "F.Fab")
			(hide yes)
			(effects
				(font
					(size 1 1)
					(thickness 0.15)
				)
			)
		)
		(property "License" "Apache-2.0"
			(at 0 0 0)
			(layer "F.Fab")
			(hide yes)
			(effects
				(font
					(size 1 1)
					(thickness 0.15)
				)
			)
		)
		(property "MPN" ""
			(at 0 0 0)
			(layer "F.Fab")
			(hide yes)
			(effects
				(font
					(size 1 1)
					(thickness 0.15)
				)
			)
		)
		(property "Manufacturer" ""
			(at 0 0 0)
			(layer "F.Fab")
			(hide yes)
			(effects
				(font
					(size 1 1)
					(thickness 0.15)
				)
			)
		)
		(sheetname "Supply")
		(sheetfile "supply.kicad_sch")
		(attr exclude_from_pos_files)
		(pad "1" smd circle
			(at 0 0)
			(size 1 1)
			(layers "F.Cu" "F.Mask")
			(net 469 "/Supply/VCC_AUX_EN")
			(pinfunction "1")
			(pintype "passive")
		)
	)
)
